(kicad_pcb
	(version 20221018)
	(generator pcbnew)
	(general
    (thickness 1.656)
  )
	(paper "A4")
	(title_block
    (title "SDI-MIPI Bridge")
    (date "2023-08-09")
    (rev "1.3.4")
    (company "Antmicro")
		(comment 9 "footprint 20 of 190 (U4), pads 1-77 of 80")
	)
	(layers
    (0 "F.Cu" signal)
    (1 "In1.Cu" power)
    (2 "In2.Cu" power)
    (3 "In3.Cu" signal)
    (4 "In4.Cu" signal)
    (31 "B.Cu" signal)
    (32 "B.Adhes" user "B.Adhesive")
    (33 "F.Adhes" user "F.Adhesive")
    (34 "B.Paste" user)
    (35 "F.Paste" user)
    (36 "B.SilkS" user "B.Silkscreen")
    (37 "F.SilkS" user "F.Silkscreen")
    (38 "B.Mask" user)
    (39 "F.Mask" user)
    (40 "Dwgs.User" user "User.Drawings")
    (41 "Cmts.User" user "User.Comments")
    (42 "Eco1.User" user "User.Eco1")
    (43 "Eco2.User" user "User.Eco2")
    (44 "Edge.Cuts" user)
    (45 "Margin" user)
    (46 "B.CrtYd" user "B.Courtyard")
    (47 "F.CrtYd" user "F.Courtyard")
    (48 "B.Fab" user)
    (49 "F.Fab" user)
  )
	(footprint "sdi-mipi-bridge-footprints:BGA-80_7x7mm_Layout10x10_P0.65mm"
    (layer "F.Cu")
    (at 145.57 115.89 -90)
    (property "Author" "Antmicro")
    (property "License" "Apache-2.0")
    (property "MPN" "LIF-MD6000-6JMG80I")
    (property "Manufacturer" "Lattice Semiconductor")
    (property "Sheetfile" "sdi-mipi-bridge.kicad_sch")
    (property "Sheetname" "")
    (property "ki_description" "FPGA, CrossLink, PLL37 I/O, 400 MHz, 5936 Cells, 1.14 V to 1.26 V, CTFBGA-80")
    (property "ki_keywords" "SMT, FPGA, IC")
    (attr smd)
    (fp_text reference "U4" (at -1.901 -4.55 90) (layer "F.SilkS")
        (effects (font (size 0.7 0.7) (thickness 0.15)) (justify right bottom))
    )
    (fp_text value "CrossLink_LIF-MD6000-6JMG80I" (at 0 4.65 90) (layer "F.Fab") hide
        (effects (font (size 0.7 0.7) (thickness 0.15)) (justify right bottom))
    )
    (pad "A1" smd circle (at -2.925 -2.925 270) (size 0.35 0.35) (layers "F.Cu" "F.Paste" "F.Mask")
      (net 155 "/MIPI1_D2_N") (pinfunction "DPHY1_DN2") (pintype "bidirectional") (solder_mask_margin -0.025) (solder_paste_margin -0.025))
    (pad "A2" smd circle (at -2.275 -2.925 270) (size 0.35 0.35) (layers "F.Cu" "F.Paste" "F.Mask")
      (net 159 "/MIPI1_D0_N") (pinfunction "DPHY1_DN0") (pintype "bidirectional") (solder_mask_margin -0.025) (solder_paste_margin -0.025))
    (pad "A3" smd circle (at -1.625 -2.925 270) (size 0.35 0.35) (layers "F.Cu" "F.Paste" "F.Mask")
      (net 161 "/MIPI1_CLK_N") (pinfunction "DPHY1_CKN") (pintype "bidirectional") (solder_mask_margin -0.025) (solder_paste_margin -0.025))
    (pad "A4" smd circle (at -0.975 -2.925 270) (size 0.35 0.35) (layers "F.Cu" "F.Paste" "F.Mask")
      (net 157 "/MIPI1_D1_N") (pinfunction "DPHY1_DN1") (pintype "bidirectional") (solder_mask_margin -0.025) (solder_paste_margin -0.025))
    (pad "A5" smd circle (at -0.325 -2.925 270) (size 0.35 0.35) (layers "F.Cu" "F.Paste" "F.Mask")
      (net 153 "/MIPI1_D3_N") (pinfunction "DPHY1_DN3") (pintype "bidirectional") (solder_mask_margin -0.025) (solder_paste_margin -0.025))
    (pad "A6" smd circle (at 0.325 -2.925 270) (size 0.35 0.35) (layers "F.Cu" "F.Paste" "F.Mask")
      (net 145 "/MIPI0_D2_N") (pinfunction "DPHY0_DN2") (pintype "bidirectional") (solder_mask_margin -0.025) (solder_paste_margin -0.025))
    (pad "A7" smd circle (at 0.975 -2.925 270) (size 0.35 0.35) (layers "F.Cu" "F.Paste" "F.Mask")
      (net 149 "/MIPI0_D0_N") (pinfunction "DPHY0_DN0") (pintype "bidirectional") (solder_mask_margin -0.025) (solder_paste_margin -0.025))
    (pad "A8" smd circle (at 1.625 -2.925 270) (size 0.35 0.35) (layers "F.Cu" "F.Paste" "F.Mask")
      (net 151 "/MIPI0_CLK_N") (pinfunction "DPHY0_CKN") (pintype "bidirectional") (solder_mask_margin -0.025) (solder_paste_margin -0.025))
    (pad "A9" smd circle (at 2.275 -2.925 270) (size 0.35 0.35) (layers "F.Cu" "F.Paste" "F.Mask")
      (net 147 "/MIPI0_D1_N") (pinfunction "DPHY0_DN1") (pintype "bidirectional") (solder_mask_margin -0.025) (solder_paste_margin -0.025))
    (pad "A10" smd circle (at 2.925 -2.925 270) (size 0.35 0.35) (layers "F.Cu" "F.Paste" "F.Mask")
      (net 143 "/MIPI0_D3_N") (pinfunction "DPHY0_DN3") (pintype "bidirectional") (solder_mask_margin -0.025) (solder_paste_margin -0.025))
    (pad "B1" smd circle (at -2.925 -2.275 270) (size 0.35 0.35) (layers "F.Cu" "F.Paste" "F.Mask")
      (net 156 "/MIPI1_D2_P") (pinfunction "DPHY1_DP2") (pintype "bidirectional") (solder_mask_margin -0.025) (solder_paste_margin -0.025))
    (pad "B2" smd circle (at -2.275 -2.275 270) (size 0.35 0.35) (layers "F.Cu" "F.Paste" "F.Mask")
      (net 160 "/MIPI1_D0_P") (pinfunction "DPHY1_DP0") (pintype "bidirectional") (solder_mask_margin -0.025) (solder_paste_margin -0.025))
    (pad "B3" smd circle (at -1.625 -2.275 270) (size 0.35 0.35) (layers "F.Cu" "F.Paste" "F.Mask")
      (net 162 "/MIPI1_CLK_P") (pinfunction "DPHY1_CKP") (pintype "bidirectional") (solder_mask_margin -0.025) (solder_paste_margin -0.025))
    (pad "B4" smd circle (at -0.975 -2.275 270) (size 0.35 0.35) (layers "F.Cu" "F.Paste" "F.Mask")
      (net 158 "/MIPI1_D1_P") (pinfunction "DPHY1_DP1") (pintype "bidirectional") (solder_mask_margin -0.025) (solder_paste_margin -0.025))
    (pad "B5" smd circle (at -0.325 -2.275 270) (size 0.35 0.35) (layers "F.Cu" "F.Paste" "F.Mask")
      (net 154 "/MIPI1_D3_P") (pinfunction "DPHY1_DP3") (pintype "bidirectional") (solder_mask_margin -0.025) (solder_paste_margin -0.025))
    (pad "B6" smd circle (at 0.325 -2.275 270) (size 0.35 0.35) (layers "F.Cu" "F.Paste" "F.Mask")
      (net 146 "/MIPI0_D2_P") (pinfunction "DPHY0_DP2") (pintype "bidirectional") (solder_mask_margin -0.025) (solder_paste_margin -0.025))
    (pad "B7" smd circle (at 0.975 -2.275 270) (size 0.35 0.35) (layers "F.Cu" "F.Paste" "F.Mask")
      (net 150 "/MIPI0_D0_P") (pinfunction "DPHY0_DP0") (pintype "bidirectional") (solder_mask_margin -0.025) (solder_paste_margin -0.025))
    (pad "B8" smd circle (at 1.625 -2.275 270) (size 0.35 0.35) (layers "F.Cu" "F.Paste" "F.Mask")
      (net 152 "/MIPI0_CLK_P") (pinfunction "DPHY0_CKP") (pintype "bidirectional") (solder_mask_margin -0.025) (solder_paste_margin -0.025))
    (pad "B9" smd circle (at 2.275 -2.275 270) (size 0.35 0.35) (layers "F.Cu" "F.Paste" "F.Mask")
      (net 148 "/MIPI0_D1_P") (pinfunction "DPHY0_DP1") (pintype "bidirectional") (solder_mask_margin -0.025) (solder_paste_margin -0.025))
    (pad "B10" smd circle (at 2.925 -2.275 270) (size 0.35 0.35) (layers "F.Cu" "F.Paste" "F.Mask")
      (net 144 "/MIPI0_D3_P") (pinfunction "DPHY0_DP3") (pintype "bidirectional") (solder_mask_margin -0.025) (solder_paste_margin -0.025))
    (pad "C1" smd circle (at -2.925 -1.625 270) (size 0.35 0.35) (layers "F.Cu" "F.Paste" "F.Mask")
      (net 1 "GNDREF") (pinfunction "GND") (pintype "power_in") (solder_mask_margin -0.025) (solder_paste_margin -0.025))
    (pad "C2" smd circle (at -2.275 -1.625 270) (size 0.35 0.35) (layers "F.Cu" "F.Paste" "F.Mask")
      (net 1 "GNDREF") (pinfunction "GNDA_DPHY1") (pintype "power_in") (solder_mask_margin -0.025) (solder_paste_margin -0.025))
    (pad "C9" smd circle (at 2.275 -1.625 270) (size 0.35 0.35) (layers "F.Cu" "F.Paste" "F.Mask")
      (net 1 "GNDREF") (pinfunction "GNDA_DPHY0") (pintype "power_in") (solder_mask_margin -0.025) (solder_paste_margin -0.025))
    (pad "C10" smd circle (at 2.925 -1.625 270) (size 0.35 0.35) (layers "F.Cu" "F.Paste" "F.Mask")
      (net 1 "GNDREF") (pinfunction "GND") (pintype "passive") (solder_mask_margin -0.025) (solder_paste_margin -0.025))
    (pad "D1" smd circle (at -2.925 -0.975 270) (size 0.35 0.35) (layers "F.Cu" "F.Paste" "F.Mask")
      (net 103 "/USER_SDA") (pinfunction "PB48/PCLKT0_1/USER_SCL") (pintype "bidirectional") (solder_mask_margin -0.025) (solder_paste_margin -0.025))
    (pad "D2" smd circle (at -2.275 -0.975 270) (size 0.35 0.35) (layers "F.Cu" "F.Paste" "F.Mask")
      (net 85 "Net-(U4-VCCA_DPHY1)") (pinfunction "VCCPLL_DPHY1") (pintype "power_in") (solder_mask_margin -0.025) (solder_paste_margin -0.025))
    (pad "D4" smd circle (at -0.975 -0.975 270) (size 0.35 0.35) (layers "F.Cu" "F.Paste" "F.Mask")
      (net 85 "Net-(U4-VCCA_DPHY1)") (pinfunction "VCCA_DPHY1") (pintype "power_in") (solder_mask_margin -0.025) (solder_paste_margin -0.025))
    (pad "D5" smd circle (at -0.325 -0.975 270) (size 0.35 0.35) (layers "F.Cu" "F.Paste" "F.Mask")
      (net 6 "+3V3") (pinfunction "VCCAUX") (pintype "power_in") (solder_mask_margin -0.025) (solder_paste_margin -0.025))
    (pad "D6" smd circle (at 0.325 -0.975 270) (size 0.35 0.35) (layers "F.Cu" "F.Paste" "F.Mask")
      (net 58 "/GNDPLL_DPHY") (pinfunction "GNDPLL_DPHY_X") (pintype "power_in") (solder_mask_margin -0.025) (solder_paste_margin -0.025))
    (pad "D7" smd circle (at 0.975 -0.975 270) (size 0.35 0.35) (layers "F.Cu" "F.Paste" "F.Mask")
      (net 104 "Net-(U4-VCCA_DPHY0)") (pinfunction "VCCPLL_DPHY0") (pintype "bidirectional") (solder_mask_margin -0.025) (solder_paste_margin -0.025))
    (pad "D9" smd circle (at 2.275 -0.975 270) (size 0.35 0.35) (layers "F.Cu" "F.Paste" "F.Mask")
      (net 44 "/JTAG_~{HOST}") (pinfunction "PB16A/PCLKT2_0") (pintype "bidirectional") (solder_mask_margin -0.025) (solder_paste_margin -0.025))
    (pad "D10" smd circle (at 2.925 -0.975 270) (size 0.35 0.35) (layers "F.Cu" "F.Paste" "F.Mask")
      (net 127 "/~{RST_TRST_SOFT}") (pinfunction "PB16B/PCLKC2_0") (pintype "bidirectional") (solder_mask_margin -0.025) (solder_paste_margin -0.025))
    (pad "E1" smd circle (at -2.925 -0.325 270) (size 0.35 0.35) (layers "F.Cu" "F.Paste" "F.Mask")
      (net 172 "/DOUT14") (pinfunction "PB34A/GR_PCLK1_0") (pintype "input") (solder_mask_margin -0.025) (solder_paste_margin -0.025))
    (pad "E2" smd circle (at -2.275 -0.325 270) (size 0.35 0.35) (layers "F.Cu" "F.Paste" "F.Mask")
      (net 87 "/LOCKED_CL") (pinfunction "PB34B") (pintype "bidirectional") (solder_mask_margin -0.025) (solder_paste_margin -0.025))
    (pad "E4" smd circle (at -0.975 -0.325 270) (size 0.35 0.35) (layers "F.Cu" "F.Paste" "F.Mask")
      (net 2 "+1V2") (pinfunction "VCC") (pintype "power_in") (solder_mask_margin -0.025) (solder_paste_margin -0.025))
    (pad "E5" smd circle (at -0.325 -0.325 270) (size 0.35 0.35) (layers "F.Cu" "F.Paste" "F.Mask")
      (net 1 "GNDREF") (pinfunction "GND") (pintype "passive") (solder_mask_margin -0.025) (solder_paste_margin -0.025))
    (pad "E6" smd circle (at 0.325 -0.325 270) (size 0.35 0.35) (layers "F.Cu" "F.Paste" "F.Mask")
      (net 2 "+1V2") (pinfunction "VCC") (pintype "passive") (solder_mask_margin -0.025) (solder_paste_margin -0.025))
    (pad "E7" smd circle (at 0.975 -0.325 270) (size 0.35 0.35) (layers "F.Cu" "F.Paste" "F.Mask")
      (net 104 "Net-(U4-VCCA_DPHY0)") (pinfunction "VCCA_DPHY0") (pintype "power_in") (solder_mask_margin -0.025) (solder_paste_margin -0.025))
    (pad "E9" smd circle (at 2.275 -0.325 270) (size 0.35 0.35) (layers "F.Cu" "F.Paste" "F.Mask")
      (net 54 "/STANDBY") (pinfunction "PB12A/GPLLT2_0") (pintype "input") (solder_mask_margin -0.025) (solder_paste_margin -0.025))
    (pad "E10" smd circle (at 2.925 -0.325 270) (size 0.35 0.35) (layers "F.Cu" "F.Paste" "F.Mask")
      (net 22 "/~{DATA_ERROR}") (pinfunction "PB12B/GPLLC2_0") (pintype "input") (solder_mask_margin -0.025) (solder_paste_margin -0.025))
    (pad "F1" smd circle (at -2.925 0.325 270) (size 0.35 0.35) (layers "F.Cu" "F.Paste" "F.Mask")
      (net 14 "/H_HSYNC") (pinfunction "PB38A") (pintype "bidirectional") (solder_mask_margin -0.025) (solder_paste_margin -0.025))
    (pad "F2" smd circle (at -2.275 0.325 270) (size 0.35 0.35) (layers "F.Cu" "F.Paste" "F.Mask")
      (net 15 "/V_VSYNC") (pinfunction "PB38B") (pintype "bidirectional") (solder_mask_margin -0.025) (solder_paste_margin -0.025))
    (pad "F4" smd circle (at -0.975 0.325 270) (size 0.35 0.35) (layers "F.Cu" "F.Paste" "F.Mask")
      (net 79 "VCC_IO") (pinfunction "VCCIO0") (pintype "power_in") (solder_mask_margin -0.025) (solder_paste_margin -0.025))
    (pad "F5" smd circle (at -0.325 0.325 270) (size 0.35 0.35) (layers "F.Cu" "F.Paste" "F.Mask")
      (net 79 "VCC_IO") (pinfunction "VCCIO1") (pintype "power_in") (solder_mask_margin -0.025) (solder_paste_margin -0.025))
    (pad "F6" smd circle (at 0.325 0.325 270) (size 0.35 0.35) (layers "F.Cu" "F.Paste" "F.Mask")
      (net 79 "VCC_IO") (pinfunction "VCCIO2") (pintype "power_in") (solder_mask_margin -0.025) (solder_paste_margin -0.025))
    (pad "F7" smd circle (at 0.975 0.325 270) (size 0.35 0.35) (layers "F.Cu" "F.Paste" "F.Mask")
      (net 79 "VCC_IO") (pinfunction "VCCIO2") (pintype "passive") (solder_mask_margin -0.025) (solder_paste_margin -0.025))
    (pad "F9" smd circle (at 2.275 0.325 270) (size 0.35 0.35) (layers "F.Cu" "F.Paste" "F.Mask")
      (net 19 "/F_DE") (pinfunction "PB6A/GR_PCLK2_0") (pintype "input") (solder_mask_margin -0.025) (solder_paste_margin -0.025))
    (pad "F10" smd circle (at 2.925 0.325 270) (size 0.35 0.35) (layers "F.Cu" "F.Paste" "F.Mask")
      (net 21 "/Y_1ANC") (pinfunction "PB6B") (pintype "bidirectional") (solder_mask_margin -0.025) (solder_paste_margin -0.025))
    (pad "G1" smd circle (at -2.925 0.975 270) (size 0.35 0.35) (layers "F.Cu" "F.Paste" "F.Mask")
      (net 97 "/MOSI") (pinfunction "PB50/MOSI") (pintype "bidirectional") (solder_mask_margin -0.025) (solder_paste_margin -0.025))
    (pad "G2" smd circle (at -2.275 0.975 270) (size 0.35 0.35) (layers "F.Cu" "F.Paste" "F.Mask")
      (net 1 "GNDREF") (pinfunction "GND") (pintype "passive") (solder_mask_margin -0.025) (solder_paste_margin -0.025))
    (pad "G4" smd circle (at -0.975 0.975 270) (size 0.35 0.35) (layers "F.Cu" "F.Paste" "F.Mask")
      (net 79 "VCC_IO") (pinfunction "VCCIO1") (pintype "passive") (solder_mask_margin -0.025) (solder_paste_margin -0.025))
    (pad "G5" smd circle (at -0.325 0.975 270) (size 0.35 0.35) (layers "F.Cu" "F.Paste" "F.Mask")
      (net 1 "GNDREF") (pinfunction "GND") (pintype "passive") (solder_mask_margin -0.025) (solder_paste_margin -0.025))
    (pad "G6" smd circle (at 0.325 0.975 270) (size 0.35 0.35) (layers "F.Cu" "F.Paste" "F.Mask")
      (net 89 "VCCGPLL") (pinfunction "VCCGPLL") (pintype "power_in") (solder_mask_margin -0.025) (solder_paste_margin -0.025))
    (pad "G7" smd circle (at 0.975 0.975 270) (size 0.35 0.35) (layers "F.Cu" "F.Paste" "F.Mask")
      (net 59 "/GNDGPLL") (pinfunction "GNDGPLL") (pintype "power_in") (solder_mask_margin -0.025) (solder_paste_margin -0.025))
    (pad "G9" smd circle (at 2.275 0.975 270) (size 0.35 0.35) (layers "F.Cu" "F.Paste" "F.Mask")
      (net 23 "/TIM_861") (pinfunction "PB2A") (pintype "bidirectional") (solder_mask_margin -0.025) (solder_paste_margin -0.025))
    (pad "G10" smd circle (at 2.925 0.975 270) (size 0.35 0.35) (layers "F.Cu" "F.Paste" "F.Mask")
      (net 24 "/~{RC_BYP}") (pinfunction "PB2B") (pintype "bidirectional") (solder_mask_margin -0.025) (solder_paste_margin -0.025))
    (pad "H1" smd circle (at -2.925 1.625 270) (size 0.35 0.35) (layers "F.Cu" "F.Paste" "F.Mask")
      (net 99 "/SPI_SS(SCL)") (pinfunction "PB52/SPI_SS/CSN/SCL") (pintype "bidirectional") (solder_mask_margin -0.025) (solder_paste_margin -0.025))
    (pad "H2" smd circle (at -2.275 1.625 270) (size 0.35 0.35) (layers "F.Cu" "F.Paste" "F.Mask")
      (net 100 "/CRESET_B") (pinfunction "CRESET_B") (pintype "input") (solder_mask_margin -0.025) (solder_paste_margin -0.025))
    (pad "H9" smd circle (at 2.275 1.625 270) (size 0.35 0.35) (layers "F.Cu" "F.Paste" "F.Mask")
      (net 47 "/SW_EN") (pinfunction "PB2D/MIPI_CLKC2_0") (pintype "bidirectional") (solder_mask_margin -0.025) (solder_paste_margin -0.025))
    (pad "H10" smd circle (at 2.925 1.625 270) (size 0.35 0.35) (layers "F.Cu" "F.Paste" "F.Mask")
      (net 41 "/IOPROC_EN_~{DIS}") (pinfunction "PB2C/MIPI_CLKT2_0") (pintype "bidirectional") (solder_mask_margin -0.025) (solder_paste_margin -0.025))
    (pad "J1" smd circle (at -2.925 2.275 270) (size 0.35 0.35) (layers "F.Cu" "F.Paste" "F.Mask")
      (net 128 "Net-(U4-PB53{slash}SPI_SCK{slash}MCK{slash}SDA)") (pinfunction "PB53/SPI_SCK/MCK/SDA") (pintype "bidirectional") (solder_mask_margin -0.025) (solder_paste_margin -0.025))
    (pad "J2" smd circle (at -2.275 2.275 270) (size 0.35 0.35) (layers "F.Cu" "F.Paste" "F.Mask")
      (net 88 "/CDONE") (pinfunction "PB49/PMU_WKUPN/CDONE") (pintype "passive") (solder_mask_margin -0.025) (solder_paste_margin -0.025))
    (pad "J3" smd circle (at -1.625 2.275 270) (size 0.35 0.35) (layers "F.Cu" "F.Paste" "F.Mask")
      (net 173 "/DOUT13") (pinfunction "PB43D") (pintype "bidirectional") (solder_mask_margin -0.025) (solder_paste_margin -0.025))
    (pad "J4" smd circle (at -0.975 2.275 270) (size 0.35 0.35) (layers "F.Cu" "F.Paste" "F.Mask")
      (net 171 "/DOUT12") (pinfunction "PB38D") (pintype "bidirectional") (solder_mask_margin -0.025) (solder_paste_margin -0.025))
    (pad "J5" smd circle (at -0.325 2.275 270) (size 0.35 0.35) (layers "F.Cu" "F.Paste" "F.Mask")
      (net 175 "/DOUT11") (pinfunction "PB34D/MIPI_CLKC1_0") (pintype "bidirectional") (solder_mask_margin -0.025) (solder_paste_margin -0.025))
    (pad "J6" smd circle (at 0.325 2.275 270) (size 0.35 0.35) (layers "F.Cu" "F.Paste" "F.Mask")
      (net 174 "/DOUT10") (pinfunction "PB29D/PCLKC1_1") (pintype "bidirectional") (solder_mask_margin -0.025) (solder_paste_margin -0.025))
    (pad "J7" smd circle (at 0.975 2.275 270) (size 0.35 0.35) (layers "F.Cu" "F.Paste" "F.Mask")
      (net 13 "/PCLK") (pinfunction "PB29A/PCLKT1_0") (pintype "bidirectional") (solder_mask_margin -0.025) (solder_paste_margin -0.025))
    (pad "J8" smd circle (at 1.625 2.275 270) (size 0.35 0.35) (layers "F.Cu" "F.Paste" "F.Mask")
      (net 53 "/Audio_EN_~{DIS}") (pinfunction "PB16D/PCLKC2_1") (pintype "bidirectional") (solder_mask_margin -0.025) (solder_paste_margin -0.025))
    (pad "J9" smd circle (at 2.275 2.275 270) (size 0.35 0.35) (layers "F.Cu" "F.Paste" "F.Mask")
      (net 105 "/USER_SW") (pinfunction "PB6D") (pintype "bidirectional") (solder_mask_margin -0.025) (solder_paste_margin -0.025))
    (pad "J10" smd circle (at 2.925 2.275 270) (size 0.35 0.35) (layers "F.Cu" "F.Paste" "F.Mask")
      (net 106 "/USER_LED") (pinfunction "PB6C") (pintype "bidirectional") (solder_mask_margin -0.025) (solder_paste_margin -0.025))
    (pad "K1" smd circle (at -2.925 2.925 270) (size 0.35 0.35) (layers "F.Cu" "F.Paste" "F.Mask")
      (net 96 "/MISO") (pinfunction "PB51/MISO") (pintype "bidirectional") (solder_mask_margin -0.025) (solder_paste_margin -0.025))
    (pad "K2" smd circle (at -2.275 2.925 270) (size 0.35 0.35) (layers "F.Cu" "F.Paste" "F.Mask")
      (net 101 "/USER_SCL") (pinfunction "PB47/PCLKT0_0/USER_SDA") (pintype "bidirectional") (solder_mask_margin -0.025) (solder_paste_margin -0.025))
    (pad "K3" smd circle (at -1.625 2.925 270) (size 0.35 0.35) (layers "F.Cu" "F.Paste" "F.Mask")
      (net 168 "/DOUT19") (pinfunction "PB43C") (pintype "bidirectional") (solder_mask_margin -0.025) (solder_paste_margin -0.025))
    (pad "K4" smd circle (at -0.975 2.925 270) (size 0.35 0.35) (layers "F.Cu" "F.Paste" "F.Mask")
      (net 166 "/DOUT18") (pinfunction "PB38C") (pintype "bidirectional") (solder_mask_margin -0.025) (solder_paste_margin -0.025))
    (pad "K5" smd circle (at -0.325 2.925 270) (size 0.35 0.35) (layers "F.Cu" "F.Paste" "F.Mask")
      (net 167 "/DOUT17") (pinfunction "PB34C/MIPI_CLKT1_0") (pintype "bidirectional") (solder_mask_margin -0.025) (solder_paste_margin -0.025))
    (pad "K6" smd circle (at 0.325 2.925 270) (size 0.35 0.35) (layers "F.Cu" "F.Paste" "F.Mask")
      (net 169 "/DOUT16") (pinfunction "PB29C/PCLKT1_1") (pintype "bidirectional") (solder_mask_margin -0.025) (solder_paste_margin -0.025))
    (pad "K7" smd circle (at 0.975 2.925 270) (size 0.35 0.35) (layers "F.Cu" "F.Paste" "F.Mask")
      (net 170 "/DOUT15") (pinfunction "PB29B/PCLKC1_0") (pintype "bidirectional") (solder_mask_margin -0.025) (solder_paste_margin -0.025))
  )
)
